(kicad_pcb
	(version 20260206)
	(generator "pcbnew")
	(generator_version "10.0")
	(general
		(thickness 1.6)
		(legacy_teardrops no)
	)
	(paper "A4")
	(title_block
		(title "04192023_DAF0TMB3IC0_F0TG_MB_C_brd_V02_OCP.brd")
		(comment 1 "Grand Teton / footprints 6447-6453 of 8354")
	)
	(layers
		(0 "F.Cu" signal "TOP")
		(4 "In1.Cu" signal "GND")
		(6 "In2.Cu" signal "IN1")
		(8 "In3.Cu" signal "GND1")
		(10 "In4.Cu" signal "IN2")
		(12 "In5.Cu" signal "GND2")
		(14 "In6.Cu" signal "IN3")
		(16 "In7.Cu" signal "GND3")
		(18 "In8.Cu" signal "VCC")
		(20 "In9.Cu" signal "VCC1")
		(22 "In10.Cu" signal "GND4")
		(24 "In11.Cu" signal "IN4")
		(26 "In12.Cu" signal "GND5")
		(28 "In13.Cu" signal "IN5")
		(30 "In14.Cu" signal "GND6")
		(32 "In15.Cu" signal "IN6")
		(34 "In16.Cu" signal "GND7")
		(2 "B.Cu" signal "BOTTOM")
		(9 "F.Adhes" user "F.Adhesive")
		(11 "B.Adhes" user "B.Adhesive")
		(13 "F.Paste" user "Package Geometry/Pastemask Top")
		(15 "B.Paste" user "Package Geometry/Pastemask Bottom")
		(5 "F.SilkS" user "Ref Des/Silkscreen Top")
		(7 "B.SilkS" user "Ref Des/Silkscreen Bottom")
		(1 "F.Mask" user "Board Geometry/Soldermask Top")
		(3 "B.Mask" user "Board Geometry/Soldermask Bottom")
		(17 "Dwgs.User" user "User.Drawings")
		(19 "Cmts.User" user "User.Comments")
		(21 "Eco1.User" user "User.Eco1")
		(23 "Eco2.User" user "User.Eco2")
		(25 "Edge.Cuts" user "Board Geometry/Outline")
		(27 "Margin" user)
		(31 "F.CrtYd" user "Package Geometry/Place Bound Top")
		(29 "B.CrtYd" user "Package Geometry/Place Bound Bottom")
		(35 "F.Fab" user "Ref Des/Assembly Top")
		(33 "B.Fab" user "Ref Des/Assembly Bottom")
	)
	(footprint ""
		(layer "B.Cu")
		(at 281.391614 -194.88531 180)
		(property "Reference" "R763"
			(at 0 0 0)
			(layer "B.SilkS")
			(hide yes)
			(effects
				(font
					(size 1.27 1.27)
				)
				(justify mirror)
			)
		)
		(property "Value" ""
			(at 0 0 0)
			(layer "B.Fab")
			(effects
				(font
					(size 1.27 1.27)
				)
				(justify mirror)
			)
		)
		(duplicate_pad_numbers_are_jumpers no)
		(fp_line
			(start 0.7874 0.4064)
			(end 0.7874 -0.4064)
			(stroke
				(width 0.1524)
				(type default)
			)
			(layer "B.SilkS")
		)
		(fp_line
			(start 0.7874 -0.4064)
			(end -0.7874 -0.4064)
			(stroke
				(width 0.1524)
				(type default)
			)
			(layer "B.SilkS")
		)
		(fp_line
			(start -0.7874 0.4064)
			(end 0.7874 0.4064)
			(stroke
				(width 0.1524)
				(type default)
			)
			(layer "B.SilkS")
		)
		(fp_line
			(start -0.7874 -0.4064)
			(end -0.7874 0.4064)
			(stroke
				(width 0.1524)
				(type default)
			)
			(layer "B.SilkS")
		)
		(fp_line
			(start 0.67945 0.3048)
			(end 0.67945 -0.305054)
			(stroke
				(width 0.1)
				(type default)
			)
			(layer "B.Fab")
		)
		(fp_line
			(start 0.67945 -0.305054)
			(end 0.12065 -0.305054)
			(stroke
				(width 0.1)
				(type default)
			)
			(layer "B.Fab")
		)
		(fp_line
			(start 0.12065 0.3048)
			(end 0.67945 0.3048)
			(stroke
				(width 0.1)
				(type default)
			)
			(layer "B.Fab")
		)
		(fp_line
			(start 0.12065 0.2794)
			(end 0.12065 0.3048)
			(stroke
				(width 0.1)
				(type default)
			)
			(layer "B.Fab")
		)
		(fp_line
			(start 0.12065 -0.2794)
			(end -0.12065 -0.2794)
			(stroke
				(width 0.1)
				(type default)
			)
			(layer "B.Fab")
		)
		(fp_line
			(start 0.12065 -0.305054)
			(end 0.12065 -0.2794)
			(stroke
				(width 0.1)
				(type default)
			)
			(layer "B.Fab")
		)
		(fp_line
			(start -0.120396 0.3048)
			(end -0.120396 0.2794)
			(stroke
				(width 0.1)
				(type default)
			)
			(layer "B.Fab")
		)
		(fp_line
			(start -0.120396 0.2794)
			(end 0.12065 0.2794)
			(stroke
				(width 0.1)
				(type default)
			)
			(layer "B.Fab")
		)
		(fp_line
			(start -0.12065 -0.2794)
			(end -0.12065 -0.3048)
			(stroke
				(width 0.1)
				(type default)
			)
			(layer "B.Fab")
		)
		(fp_line
			(start -0.12065 -0.3048)
			(end -0.67945 -0.3048)
			(stroke
				(width 0.1)
				(type default)
			)
			(layer "B.Fab")
		)
		(fp_line
			(start -0.67945 0.3048)
			(end -0.120396 0.3048)
			(stroke
				(width 0.1)
				(type default)
			)
			(layer "B.Fab")
		)
		(fp_line
			(start -0.67945 -0.3048)
			(end -0.67945 0.3048)
			(stroke
				(width 0.1)
				(type default)
			)
			(layer "B.Fab")
		)
		(pad "1" smd circle
			(at 0.40005 0)
			(size 0 0)
			(layers "B.Cu" "B.Mask" "B.Paste")
			(net "PD_CHD_CPU0_DIMM_SAA")
		)
		(pad "2" smd circle
			(at -0.40005 0)
			(size 0 0)
			(layers "B.Cu" "B.Mask" "B.Paste")
			(net "GND")
		)
	)
	(footprint ""
		(layer "B.Cu")
		(at 67.417442 -387.768592 180)
		(property "Reference" "C264"
			(at 0 0 0)
			(layer "B.SilkS")
			(hide yes)
			(effects
				(font
					(size 1.27 1.27)
				)
				(justify mirror)
			)
		)
		(property "Value" ""
			(at 0 0 0)
			(layer "B.Fab")
			(effects
				(font
					(size 1.27 1.27)
				)
				(justify mirror)
			)
		)
		(duplicate_pad_numbers_are_jumpers no)
		(fp_line
			(start 0.299974 0.150114)
			(end 0.299974 -0.150114)
			(stroke
				(width 0.1)
				(type default)
			)
			(layer "B.Fab")
		)
		(fp_line
			(start 0.299974 -0.150114)
			(end -0.299974 -0.150114)
			(stroke
				(width 0.1)
				(type default)
			)
			(layer "B.Fab")
		)
		(fp_line
			(start -0.299974 0.150114)
			(end 0.299974 0.150114)
			(stroke
				(width 0.1)
				(type default)
			)
			(layer "B.Fab")
		)
		(fp_line
			(start -0.299974 -0.150114)
			(end -0.299974 0.150114)
			(stroke
				(width 0.1)
				(type default)
			)
			(layer "B.Fab")
		)
		(pad "1" smd rect
			(at 0.2667 0)
			(size 0.3048 0.381)
			(layers "B.Cu" "B.Mask" "B.Paste")
			(net "P0V9_CPU1_RT0_2A")
		)
		(pad "2" smd rect
			(at -0.2667 0)
			(size 0.3048 0.381)
			(layers "B.Cu" "B.Mask" "B.Paste")
			(net "GND")
		)
	)
	(footprint ""
		(layer "B.Cu")
		(at 325.635112 -34.651442 90)
		(property "Reference" "R3939"
			(at 0 0 90)
			(layer "B.SilkS")
			(hide yes)
			(effects
				(font
					(size 1.27 1.27)
				)
				(justify mirror)
			)
		)
		(property "Value" ""
			(at 0 0 90)
			(layer "B.Fab")
			(effects
				(font
					(size 1.27 1.27)
				)
				(justify mirror)
			)
		)
		(duplicate_pad_numbers_are_jumpers no)
		(fp_line
			(start 0.7874 -0.4064)
			(end -0.7874 -0.4064)
			(stroke
				(width 0.1524)
				(type default)
			)
			(layer "B.SilkS")
		)
		(fp_line
			(start -0.7874 -0.4064)
			(end -0.7874 0.4064)
			(stroke
				(width 0.1524)
				(type default)
			)
			(layer "B.SilkS")
		)
		(fp_line
			(start 0.7874 0.4064)
			(end 0.7874 -0.4064)
			(stroke
				(width 0.1524)
				(type default)
			)
			(layer "B.SilkS")
		)
		(fp_line
			(start -0.7874 0.4064)
			(end 0.7874 0.4064)
			(stroke
				(width 0.1524)
				(type default)
			)
			(layer "B.SilkS")
		)
		(fp_line
			(start 0.67945 -0.305054)
			(end 0.12065 -0.305054)
			(stroke
				(width 0.1)
				(type default)
			)
			(layer "B.Fab")
		)
		(fp_line
			(start 0.12065 -0.305054)
			(end 0.12065 -0.2794)
			(stroke
				(width 0.1)
				(type default)
			)
			(layer "B.Fab")
		)
		(fp_line
			(start -0.12065 -0.3048)
			(end -0.67945 -0.3048)
			(stroke
				(width 0.1)
				(type default)
			)
			(layer "B.Fab")
		)
		(fp_line
			(start -0.67945 -0.3048)
			(end -0.67945 0.3048)
			(stroke
				(width 0.1)
				(type default)
			)
			(layer "B.Fab")
		)
		(fp_line
			(start 0.12065 -0.2794)
			(end -0.12065 -0.2794)
			(stroke
				(width 0.1)
				(type default)
			)
			(layer "B.Fab")
		)
		(fp_line
			(start -0.12065 -0.2794)
			(end -0.12065 -0.3048)
			(stroke
				(width 0.1)
				(type default)
			)
			(layer "B.Fab")
		)
		(fp_line
			(start 0.12065 0.2794)
			(end 0.12065 0.3048)
			(stroke
				(width 0.1)
				(type default)
			)
			(layer "B.Fab")
		)
		(fp_line
			(start -0.120396 0.2794)
			(end 0.12065 0.2794)
			(stroke
				(width 0.1)
				(type default)
			)
			(layer "B.Fab")
		)
		(fp_line
			(start 0.67945 0.3048)
			(end 0.67945 -0.305054)
			(stroke
				(width 0.1)
				(type default)
			)
			(layer "B.Fab")
		)
		(fp_line
			(start 0.12065 0.3048)
			(end 0.67945 0.3048)
			(stroke
				(width 0.1)
				(type default)
			)
			(layer "B.Fab")
		)
		(fp_line
			(start -0.120396 0.3048)
			(end -0.120396 0.2794)
			(stroke
				(width 0.1)
				(type default)
			)
			(layer "B.Fab")
		)
		(fp_line
			(start -0.67945 0.3048)
			(end -0.120396 0.3048)
			(stroke
				(width 0.1)
				(type default)
			)
			(layer "B.Fab")
		)
		(pad "1" smd rect
			(at 0.40005 0 90)
			(size 0.4572 0.508)
			(layers "B.Cu" "B.Mask" "B.Paste")
			(net "P12V_E1S_0_ISENSE_MAM_MAM")
		)
		(pad "2" smd rect
			(at -0.40005 0 90)
			(size 0.4572 0.508)
			(layers "B.Cu" "B.Mask" "B.Paste")
			(net "P12V_E1S_0_ISENSE_MAM")
		)
	)
	(footprint ""
		(layer "B.Cu")
		(at 449.518278 -8.3566 -90)
		(property "Reference" "R34"
			(at 0 0 90)
			(layer "B.SilkS")
			(hide yes)
			(effects
				(font
					(size 1.27 1.27)
				)
				(justify mirror)
			)
		)
		(property "Value" ""
			(at 0 0 90)
			(layer "B.Fab")
			(effects
				(font
					(size 1.27 1.27)
				)
				(justify mirror)
			)
		)
		(duplicate_pad_numbers_are_jumpers no)
		(fp_line
			(start -0.7874 0.4064)
			(end 0.7874 0.4064)
			(stroke
				(width 0.1524)
				(type default)
			)
			(layer "B.SilkS")
		)
		(fp_line
			(start 0.7874 0.4064)
			(end 0.7874 -0.4064)
			(stroke
				(width 0.1524)
				(type default)
			)
			(layer "B.SilkS")
		)
		(fp_line
			(start -0.7874 -0.4064)
			(end -0.7874 0.4064)
			(stroke
				(width 0.1524)
				(type default)
			)
			(layer "B.SilkS")
		)
		(fp_line
			(start 0.7874 -0.4064)
			(end -0.7874 -0.4064)
			(stroke
				(width 0.1524)
				(type default)
			)
			(layer "B.SilkS")
		)
		(fp_line
			(start -0.67945 0.3048)
			(end -0.120396 0.3048)
			(stroke
				(width 0.1)
				(type default)
			)
			(layer "B.Fab")
		)
		(fp_line
			(start -0.120396 0.3048)
			(end -0.120396 0.2794)
			(stroke
				(width 0.1)
				(type default)
			)
			(layer "B.Fab")
		)
		(fp_line
			(start 0.12065 0.3048)
			(end 0.67945 0.3048)
			(stroke
				(width 0.1)
				(type default)
			)
			(layer "B.Fab")
		)
		(fp_line
			(start 0.67945 0.3048)
			(end 0.67945 -0.305054)
			(stroke
				(width 0.1)
				(type default)
			)
			(layer "B.Fab")
		)
		(fp_line
			(start -0.120396 0.2794)
			(end 0.12065 0.2794)
			(stroke
				(width 0.1)
				(type default)
			)
			(layer "B.Fab")
		)
		(fp_line
			(start 0.12065 0.2794)
			(end 0.12065 0.3048)
			(stroke
				(width 0.1)
				(type default)
			)
			(layer "B.Fab")
		)
		(fp_line
			(start -0.12065 -0.2794)
			(end -0.12065 -0.3048)
			(stroke
				(width 0.1)
				(type default)
			)
			(layer "B.Fab")
		)
		(fp_line
			(start 0.12065 -0.2794)
			(end -0.12065 -0.2794)
			(stroke
				(width 0.1)
				(type default)
			)
			(layer "B.Fab")
		)
		(fp_line
			(start -0.67945 -0.3048)
			(end -0.67945 0.3048)
			(stroke
				(width 0.1)
				(type default)
			)
			(layer "B.Fab")
		)
		(fp_line
			(start -0.12065 -0.3048)
			(end -0.67945 -0.3048)
			(stroke
				(width 0.1)
				(type default)
			)
			(layer "B.Fab")
		)
		(fp_line
			(start 0.12065 -0.305054)
			(end 0.12065 -0.2794)
			(stroke
				(width 0.1)
				(type default)
			)
			(layer "B.Fab")
		)
		(fp_line
			(start 0.67945 -0.305054)
			(end 0.12065 -0.305054)
			(stroke
				(width 0.1)
				(type default)
			)
			(layer "B.Fab")
		)
		(pad "1" smd circle
			(at 0.40005 0 90)
			(size 0 0)
			(layers "B.Cu" "B.Mask" "B.Paste")
			(net "OCP_SFF_ID1")
		)
		(pad "2" smd circle
			(at -0.40005 0 90)
			(size 0 0)
			(layers "B.Cu" "B.Mask" "B.Paste")
			(net "GND")
		)
	)
	(footprint ""
		(layer "B.Cu")
		(at 90.209878 -143.86941 180)
		(property "Reference" "R8182"
			(at 0 0 0)
			(layer "B.SilkS")
			(hide yes)
			(effects
				(font
					(size 1.27 1.27)
				)
				(justify mirror)
			)
		)
		(property "Value" ""
			(at 0 0 0)
			(layer "B.Fab")
			(effects
				(font
					(size 1.27 1.27)
				)
				(justify mirror)
			)
		)
		(duplicate_pad_numbers_are_jumpers no)
		(fp_line
			(start 0.7874 0.4064)
			(end 0.7874 -0.4064)
			(stroke
				(width 0.1524)
				(type default)
			)
			(layer "B.SilkS")
		)
		(fp_line
			(start 0.7874 -0.4064)
			(end -0.7874 -0.4064)
			(stroke
				(width 0.1524)
				(type default)
			)
			(layer "B.SilkS")
		)
		(fp_line
			(start -0.7874 0.4064)
			(end 0.7874 0.4064)
			(stroke
				(width 0.1524)
				(type default)
			)
			(layer "B.SilkS")
		)
		(fp_line
			(start -0.7874 -0.4064)
			(end -0.7874 0.4064)
			(stroke
				(width 0.1524)
				(type default)
			)
			(layer "B.SilkS")
		)
		(fp_line
			(start 0.67945 0.3048)
			(end 0.67945 -0.305054)
			(stroke
				(width 0.1)
				(type default)
			)
			(layer "B.Fab")
		)
		(fp_line
			(start 0.67945 -0.305054)
			(end 0.12065 -0.305054)
			(stroke
				(width 0.1)
				(type default)
			)
			(layer "B.Fab")
		)
		(fp_line
			(start 0.12065 0.3048)
			(end 0.67945 0.3048)
			(stroke
				(width 0.1)
				(type default)
			)
			(layer "B.Fab")
		)
		(fp_line
			(start 0.12065 0.2794)
			(end 0.12065 0.3048)
			(stroke
				(width 0.1)
				(type default)
			)
			(layer "B.Fab")
		)
		(fp_line
			(start 0.12065 -0.2794)
			(end -0.12065 -0.2794)
			(stroke
				(width 0.1)
				(type default)
			)
			(layer "B.Fab")
		)
		(fp_line
			(start 0.12065 -0.305054)
			(end 0.12065 -0.2794)
			(stroke
				(width 0.1)
				(type default)
			)
			(layer "B.Fab")
		)
		(fp_line
			(start -0.120396 0.3048)
			(end -0.120396 0.2794)
			(stroke
				(width 0.1)
				(type default)
			)
			(layer "B.Fab")
		)
		(fp_line
			(start -0.120396 0.2794)
			(end 0.12065 0.2794)
			(stroke
				(width 0.1)
				(type default)
			)
			(layer "B.Fab")
		)
		(fp_line
			(start -0.12065 -0.2794)
			(end -0.12065 -0.3048)
			(stroke
				(width 0.1)
				(type default)
			)
			(layer "B.Fab")
		)
		(fp_line
			(start -0.12065 -0.3048)
			(end -0.67945 -0.3048)
			(stroke
				(width 0.1)
				(type default)
			)
			(layer "B.Fab")
		)
		(fp_line
			(start -0.67945 0.3048)
			(end -0.120396 0.3048)
			(stroke
				(width 0.1)
				(type default)
			)
			(layer "B.Fab")
		)
		(fp_line
			(start -0.67945 -0.3048)
			(end -0.67945 0.3048)
			(stroke
				(width 0.1)
				(type default)
			)
			(layer "B.Fab")
		)
		(pad "1" smd circle
			(at 0.40005 0)
			(size 0 0)
			(layers "B.Cu" "B.Mask" "B.Paste")
			(net "PVDDCR_CPU0_P1_RESET_N")
		)
		(pad "2" smd circle
			(at -0.40005 0)
			(size 0 0)
			(layers "B.Cu" "B.Mask" "B.Paste")
			(net "PVDDCR_CPU0_P1_RESET_N_R")
		)
	)
	(footprint ""
		(layer "B.Cu")
		(at 90.249756 -326.346058 -90)
		(property "Reference" "PC394_2"
			(at 0 0 90)
			(layer "B.SilkS")
			(hide yes)
			(effects
				(font
					(size 1.27 1.27)
				)
				(justify mirror)
			)
		)
		(property "Value" ""
			(at 0 0 90)
			(layer "B.Fab")
			(effects
				(font
					(size 1.27 1.27)
				)
				(justify mirror)
			)
		)
		(duplicate_pad_numbers_are_jumpers no)
		(fp_line
			(start -1.524 0.762)
			(end 1.524 0.762)
			(stroke
				(width 0.1524)
				(type default)
			)
			(layer "B.SilkS")
		)
		(fp_line
			(start 1.524 0.762)
			(end 1.524 -0.762)
			(stroke
				(width 0.1524)
				(type default)
			)
			(layer "B.SilkS")
		)
		(fp_line
			(start -1.524 -0.762)
			(end -1.524 0.762)
			(stroke
				(width 0.1524)
				(type default)
			)
			(layer "B.SilkS")
		)
		(fp_line
			(start 1.524 -0.762)
			(end -1.524 -0.762)
			(stroke
				(width 0.1524)
				(type default)
			)
			(layer "B.SilkS")
		)
		(fp_line
			(start -1.1049 0.724916)
			(end -1.1049 -0.724916)
			(stroke
				(width 0.1)
				(type default)
			)
			(layer "B.Fab")
		)
		(fp_line
			(start 1.1049 0.724916)
			(end -1.1049 0.724916)
			(stroke
				(width 0.1)
				(type default)
			)
			(layer "B.Fab")
		)
		(fp_line
			(start -1.1049 -0.724916)
			(end 1.1049 -0.724916)
			(stroke
				(width 0.1)
				(type default)
			)
			(layer "B.Fab")
		)
		(fp_line
			(start 1.1049 -0.724916)
			(end 1.1049 0.724916)
			(stroke
				(width 0.1)
				(type default)
			)
			(layer "B.Fab")
		)
		(pad "1" smd rect
			(at 0.889 0 270)
			(size 1.016 1.27)
			(layers "B.Cu" "B.Mask" "B.Paste")
			(net "PVDDCR_CPU1_P1")
		)
		(pad "2" smd rect
			(at -0.889 0 270)
			(size 1.016 1.27)
			(layers "B.Cu" "B.Mask" "B.Paste")
			(net "GND")
		)
	)
	(footprint ""
		(layer "B.Cu")
		(at 20.919186 -195.012564 180)
		(property "Reference" "R1585"
			(at 0 0 0)
			(layer "B.SilkS")
			(hide yes)
			(effects
				(font
					(size 1.27 1.27)
				)
				(justify mirror)
			)
		)
		(property "Value" ""
			(at 0 0 0)
			(layer "B.Fab")
			(effects
				(font
					(size 1.27 1.27)
				)
				(justify mirror)
			)
		)
		(duplicate_pad_numbers_are_jumpers no)
		(fp_line
			(start 0.7874 0.4064)
			(end 0.7874 -0.4064)
			(stroke
				(width 0.1524)
				(type default)
			)
			(layer "B.SilkS")
		)
		(fp_line
			(start 0.7874 -0.4064)
			(end -0.7874 -0.4064)
			(stroke
				(width 0.1524)
				(type default)
			)
			(layer "B.SilkS")
		)
		(fp_line
			(start -0.7874 0.4064)
			(end 0.7874 0.4064)
			(stroke
				(width 0.1524)
				(type default)
			)
			(layer "B.SilkS")
		)
		(fp_line
			(start -0.7874 -0.4064)
			(end -0.7874 0.4064)
			(stroke
				(width 0.1524)
				(type default)
			)
			(layer "B.SilkS")
		)
		(fp_line
			(start 0.67945 0.3048)
			(end 0.67945 -0.305054)
			(stroke
				(width 0.1)
				(type default)
			)
			(layer "B.Fab")
		)
		(fp_line
			(start 0.67945 -0.305054)
			(end 0.12065 -0.305054)
			(stroke
				(width 0.1)
				(type default)
			)
			(layer "B.Fab")
		)
		(fp_line
			(start 0.12065 0.3048)
			(end 0.67945 0.3048)
			(stroke
				(width 0.1)
				(type default)
			)
			(layer "B.Fab")
		)
		(fp_line
			(start 0.12065 0.2794)
			(end 0.12065 0.3048)
			(stroke
				(width 0.1)
				(type default)
			)
			(layer "B.Fab")
		)
		(fp_line
			(start 0.12065 -0.2794)
			(end -0.12065 -0.2794)
			(stroke
				(width 0.1)
				(type default)
			)
			(layer "B.Fab")
		)
		(fp_line
			(start 0.12065 -0.305054)
			(end 0.12065 -0.2794)
			(stroke
				(width 0.1)
				(type default)
			)
			(layer "B.Fab")
		)
		(fp_line
			(start -0.120396 0.3048)
			(end -0.120396 0.2794)
			(stroke
				(width 0.1)
				(type default)
			)
			(layer "B.Fab")
		)
		(fp_line
			(start -0.120396 0.2794)
			(end 0.12065 0.2794)
			(stroke
				(width 0.1)
				(type default)
			)
			(layer "B.Fab")
		)
		(fp_line
			(start -0.12065 -0.2794)
			(end -0.12065 -0.3048)
			(stroke
				(width 0.1)
				(type default)
			)
			(layer "B.Fab")
		)
		(fp_line
			(start -0.12065 -0.3048)
			(end -0.67945 -0.3048)
			(stroke
				(width 0.1)
				(type default)
			)
			(layer "B.Fab")
		)
		(fp_line
			(start -0.67945 0.3048)
			(end -0.120396 0.3048)
			(stroke
				(width 0.1)
				(type default)
			)
			(layer "B.Fab")
		)
		(fp_line
			(start -0.67945 -0.3048)
			(end -0.67945 0.3048)
			(stroke
				(width 0.1)
				(type default)
			)
			(layer "B.Fab")
		)
		(pad "1" smd circle
			(at 0.40005 0)
			(size 0 0)
			(layers "B.Cu" "B.Mask" "B.Paste")
			(net "I3C_SPD_DDRAF_CPU1_SCL")
		)
		(pad "2" smd circle
			(at -0.40005 0)
			(size 0 0)
			(layers "B.Cu" "B.Mask" "B.Paste")
			(net "I3C_SPD_DDRF_CPU1_SCL")
		)
	)
)
